(kicad_pcb
	(version 20260206)
	(generator "pcbnew")
	(generator_version "10.0")
	(general
		(thickness 1.6)
		(legacy_teardrops no)
	)
	(paper "A4")
	(title_block
		(title "01162023_DA0F0TEBIF0_F0T_Expander_BD_F_brd_V02_OCP.brd")
		(comment 1 "Grand Teton / footprints 7114-7120 of 9728")
	)
	(layers
		(0 "F.Cu" signal "TOP")
		(4 "In1.Cu" signal "GND")
		(6 "In2.Cu" signal "VCC")
		(8 "In3.Cu" signal "VCC1")
		(10 "In4.Cu" signal "GND1")
		(12 "In5.Cu" signal "IN1")
		(14 "In6.Cu" signal "GND2")
		(16 "In7.Cu" signal "IN2")
		(18 "In8.Cu" signal "GND3")
		(20 "In9.Cu" signal "IN3")
		(22 "In10.Cu" signal "GND4")
		(24 "In11.Cu" signal "IN4")
		(26 "In12.Cu" signal "GND5")
		(28 "In13.Cu" signal "IN5")
		(30 "In14.Cu" signal "GND6")
		(32 "In15.Cu" signal "IN6")
		(34 "In16.Cu" signal "GND7")
		(2 "B.Cu" signal "BOTTOM")
		(9 "F.Adhes" user "F.Adhesive")
		(11 "B.Adhes" user "B.Adhesive")
		(13 "F.Paste" user "Package Geometry/Pastemask Top")
		(15 "B.Paste" user "Package Geometry/Pastemask Bottom")
		(5 "F.SilkS" user "Ref Des/Silkscreen Top")
		(7 "B.SilkS" user "Ref Des/Silkscreen Bottom")
		(1 "F.Mask" user "Board Geometry/Soldermask Top")
		(3 "B.Mask" user "Board Geometry/Soldermask Bottom")
		(17 "Dwgs.User" user "User.Drawings")
		(19 "Cmts.User" user "User.Comments")
		(21 "Eco1.User" user "User.Eco1")
		(23 "Eco2.User" user "User.Eco2")
		(25 "Edge.Cuts" user "Board Geometry/Outline")
		(27 "Margin" user)
		(31 "F.CrtYd" user "Package Geometry/Place Bound Top")
		(29 "B.CrtYd" user "Package Geometry/Place Bound Bottom")
		(35 "F.Fab" user "Ref Des/Assembly Top")
		(33 "B.Fab" user "Ref Des/Assembly Bottom")
	)
	(footprint ""
		(layer "B.Cu")
		(at 127.0762 -325.61149 -90)
		(property "Reference" "C4256"
			(at 0 0 90)
			(layer "B.SilkS")
			(hide yes)
			(effects
				(font
					(size 1.27 1.27)
				)
				(justify mirror)
			)
		)
		(property "Value" ""
			(at 0 0 90)
			(layer "B.Fab")
			(effects
				(font
					(size 1.27 1.27)
				)
				(justify mirror)
			)
		)
		(duplicate_pad_numbers_are_jumpers no)
		(fp_line
			(start -1.2954 0.5842)
			(end 1.2954 0.5842)
			(stroke
				(width 0.1524)
				(type default)
			)
			(layer "B.SilkS")
		)
		(fp_line
			(start 1.2954 0.5842)
			(end 1.2954 -0.5842)
			(stroke
				(width 0.1524)
				(type default)
			)
			(layer "B.SilkS")
		)
		(fp_line
			(start -1.2954 -0.5842)
			(end -1.2954 0.5842)
			(stroke
				(width 0.1524)
				(type default)
			)
			(layer "B.SilkS")
		)
		(fp_line
			(start 1.2954 -0.5842)
			(end -1.2954 -0.5842)
			(stroke
				(width 0.1524)
				(type default)
			)
			(layer "B.SilkS")
		)
		(fp_line
			(start -0.8636 0.4572)
			(end 0.8636 0.4572)
			(stroke
				(width 0.1)
				(type default)
			)
			(layer "B.Fab")
		)
		(fp_line
			(start 0.8636 0.4572)
			(end 0.8636 0.4064)
			(stroke
				(width 0.1)
				(type default)
			)
			(layer "B.Fab")
		)
		(fp_line
			(start -1.1938 0.4064)
			(end -0.8636 0.4064)
			(stroke
				(width 0.1)
				(type default)
			)
			(layer "B.Fab")
		)
		(fp_line
			(start -0.8636 0.4064)
			(end -0.8636 0.4572)
			(stroke
				(width 0.1)
				(type default)
			)
			(layer "B.Fab")
		)
		(fp_line
			(start 0.8636 0.4064)
			(end 1.1938 0.4064)
			(stroke
				(width 0.1)
				(type default)
			)
			(layer "B.Fab")
		)
		(fp_line
			(start 1.1938 0.4064)
			(end 1.1938 -0.4064)
			(stroke
				(width 0.1)
				(type default)
			)
			(layer "B.Fab")
		)
		(fp_line
			(start -1.1938 -0.4064)
			(end -1.1938 0.4064)
			(stroke
				(width 0.1)
				(type default)
			)
			(layer "B.Fab")
		)
		(fp_line
			(start -0.8636 -0.4064)
			(end -1.1938 -0.4064)
			(stroke
				(width 0.1)
				(type default)
			)
			(layer "B.Fab")
		)
		(fp_line
			(start 0.8636 -0.4064)
			(end 0.8636 -0.4572)
			(stroke
				(width 0.1)
				(type default)
			)
			(layer "B.Fab")
		)
		(fp_line
			(start 1.1938 -0.4064)
			(end 0.8636 -0.4064)
			(stroke
				(width 0.1)
				(type default)
			)
			(layer "B.Fab")
		)
		(fp_line
			(start -0.8636 -0.4572)
			(end -0.8636 -0.4064)
			(stroke
				(width 0.1)
				(type default)
			)
			(layer "B.Fab")
		)
		(fp_line
			(start 0.8636 -0.4572)
			(end -0.8636 -0.4572)
			(stroke
				(width 0.1)
				(type default)
			)
			(layer "B.Fab")
		)
		(pad "1" smd rect
			(at 0.7366 0 180)
			(size 0.7112 0.8128)
			(layers "B.Cu" "B.Mask" "B.Paste")
			(net "P0V8_SERDES_VDDA_PEX1_C2")
		)
		(pad "2" smd rect
			(at -0.7366 0 180)
			(size 0.7112 0.8128)
			(layers "B.Cu" "B.Mask" "B.Paste")
			(net "GND")
		)
	)
	(footprint ""
		(layer "B.Cu")
		(at 236.415072 -217.104214 -90)
		(property "Reference" "C2022"
			(at 0 0 90)
			(layer "B.SilkS")
			(hide yes)
			(effects
				(font
					(size 1.27 1.27)
				)
				(justify mirror)
			)
		)
		(property "Value" ""
			(at 0 0 90)
			(layer "B.Fab")
			(effects
				(font
					(size 1.27 1.27)
				)
				(justify mirror)
			)
		)
		(duplicate_pad_numbers_are_jumpers no)
		(fp_line
			(start -0.69215 0.2921)
			(end 0.69215 0.2921)
			(stroke
				(width 0.1524)
				(type default)
			)
			(layer "B.SilkS")
		)
		(fp_line
			(start 0.69215 0.2921)
			(end 0.69215 -0.2921)
			(stroke
				(width 0.1524)
				(type default)
			)
			(layer "B.SilkS")
		)
		(fp_line
			(start -0.69215 -0.2921)
			(end -0.69215 0.2921)
			(stroke
				(width 0.1524)
				(type default)
			)
			(layer "B.SilkS")
		)
		(fp_line
			(start 0.69215 -0.2921)
			(end -0.69215 -0.2921)
			(stroke
				(width 0.1524)
				(type default)
			)
			(layer "B.SilkS")
		)
		(fp_line
			(start -0.51435 0.2794)
			(end 0.51435 0.2794)
			(stroke
				(width 0.1)
				(type default)
			)
			(layer "B.Fab")
		)
		(fp_line
			(start 0.51435 0.2794)
			(end 0.51435 -0.2794)
			(stroke
				(width 0.1)
				(type default)
			)
			(layer "B.Fab")
		)
		(fp_line
			(start -0.51435 -0.2794)
			(end -0.51435 0.2794)
			(stroke
				(width 0.1)
				(type default)
			)
			(layer "B.Fab")
		)
		(fp_line
			(start 0.51435 -0.2794)
			(end -0.51435 -0.2794)
			(stroke
				(width 0.1)
				(type default)
			)
			(layer "B.Fab")
		)
		(pad "1" smd circle
			(at 0.40005 0 90)
			(size 0 0)
			(layers "B.Cu" "B.Mask" "B.Paste")
			(net "P1V2_BIC_PLL")
		)
		(pad "2" smd circle
			(at -0.40005 0 90)
			(size 0 0)
			(layers "B.Cu" "B.Mask" "B.Paste")
			(net "GND")
		)
		(zone
			(layer "B.Cu")
			(hatch none 0.5)
			(connect_pads
				(clearance 0)
			)
			(min_thickness 0.25)
			(keepout
				(tracks not_allowed)
				(vias allowed)
				(pads allowed)
				(copperpour not_allowed)
				(footprints allowed)
			)
			(placement
				(enabled no)
				(sheetname "")
			)
			(fill
				(thermal_gap 0.5)
				(thermal_bridge_width 0.5)
				(island_removal_mode 0)
			)
			(polygon
				(pts
					(xy 236.327442 -216.913714) (xy 236.269276 -217.005154) (xy 236.269276 -217.204544) (xy 236.327442 -217.294714)
					(xy 236.502702 -217.294714) (xy 236.561122 -217.204544) (xy 236.561122 -217.005154) (xy 236.502956 -216.913714)
				)
			)
		)
	)
	(footprint ""
		(layer "B.Cu")
		(at 343.323672 -326.945498 -90)
		(property "Reference" "C4315"
			(at 0 0 90)
			(layer "B.SilkS")
			(hide yes)
			(effects
				(font
					(size 1.27 1.27)
				)
				(justify mirror)
			)
		)
		(property "Value" ""
			(at 0 0 90)
			(layer "B.Fab")
			(effects
				(font
					(size 1.27 1.27)
				)
				(justify mirror)
			)
		)
		(duplicate_pad_numbers_are_jumpers no)
		(fp_line
			(start -1.2954 0.5842)
			(end 1.2954 0.5842)
			(stroke
				(width 0.1524)
				(type default)
			)
			(layer "B.SilkS")
		)
		(fp_line
			(start 1.2954 0.5842)
			(end 1.2954 -0.5842)
			(stroke
				(width 0.1524)
				(type default)
			)
			(layer "B.SilkS")
		)
		(fp_line
			(start -1.2954 -0.5842)
			(end -1.2954 0.5842)
			(stroke
				(width 0.1524)
				(type default)
			)
			(layer "B.SilkS")
		)
		(fp_line
			(start 1.2954 -0.5842)
			(end -1.2954 -0.5842)
			(stroke
				(width 0.1524)
				(type default)
			)
			(layer "B.SilkS")
		)
		(fp_line
			(start -0.8636 0.4572)
			(end 0.8636 0.4572)
			(stroke
				(width 0.1)
				(type default)
			)
			(layer "B.Fab")
		)
		(fp_line
			(start 0.8636 0.4572)
			(end 0.8636 0.4064)
			(stroke
				(width 0.1)
				(type default)
			)
			(layer "B.Fab")
		)
		(fp_line
			(start -1.1938 0.4064)
			(end -0.8636 0.4064)
			(stroke
				(width 0.1)
				(type default)
			)
			(layer "B.Fab")
		)
		(fp_line
			(start -0.8636 0.4064)
			(end -0.8636 0.4572)
			(stroke
				(width 0.1)
				(type default)
			)
			(layer "B.Fab")
		)
		(fp_line
			(start 0.8636 0.4064)
			(end 1.1938 0.4064)
			(stroke
				(width 0.1)
				(type default)
			)
			(layer "B.Fab")
		)
		(fp_line
			(start 1.1938 0.4064)
			(end 1.1938 -0.4064)
			(stroke
				(width 0.1)
				(type default)
			)
			(layer "B.Fab")
		)
		(fp_line
			(start -1.1938 -0.4064)
			(end -1.1938 0.4064)
			(stroke
				(width 0.1)
				(type default)
			)
			(layer "B.Fab")
		)
		(fp_line
			(start -0.8636 -0.4064)
			(end -1.1938 -0.4064)
			(stroke
				(width 0.1)
				(type default)
			)
			(layer "B.Fab")
		)
		(fp_line
			(start 0.8636 -0.4064)
			(end 0.8636 -0.4572)
			(stroke
				(width 0.1)
				(type default)
			)
			(layer "B.Fab")
		)
		(fp_line
			(start 1.1938 -0.4064)
			(end 0.8636 -0.4064)
			(stroke
				(width 0.1)
				(type default)
			)
			(layer "B.Fab")
		)
		(fp_line
			(start -0.8636 -0.4572)
			(end -0.8636 -0.4064)
			(stroke
				(width 0.1)
				(type default)
			)
			(layer "B.Fab")
		)
		(fp_line
			(start 0.8636 -0.4572)
			(end -0.8636 -0.4572)
			(stroke
				(width 0.1)
				(type default)
			)
			(layer "B.Fab")
		)
		(pad "1" smd rect
			(at 0.7366 0 180)
			(size 0.7112 0.8128)
			(layers "B.Cu" "B.Mask" "B.Paste")
			(net "P0V8_SERDES_VDDA_PEX2_C5")
		)
		(pad "2" smd rect
			(at -0.7366 0 180)
			(size 0.7112 0.8128)
			(layers "B.Cu" "B.Mask" "B.Paste")
			(net "GND")
		)
	)
	(footprint ""
		(layer "B.Cu")
		(at 165.774878 -293.99992 -90)
		(property "Reference" "C1381"
			(at 0 0 90)
			(layer "B.SilkS")
			(hide yes)
			(effects
				(font
					(size 1.27 1.27)
				)
				(justify mirror)
			)
		)
		(property "Value" ""
			(at 0 0 90)
			(layer "B.Fab")
			(effects
				(font
					(size 1.27 1.27)
				)
				(justify mirror)
			)
		)
		(duplicate_pad_numbers_are_jumpers no)
		(fp_line
			(start -0.299974 0.150114)
			(end 0.299974 0.150114)
			(stroke
				(width 0.1)
				(type default)
			)
			(layer "B.Fab")
		)
		(fp_line
			(start 0.299974 0.150114)
			(end 0.299974 -0.150114)
			(stroke
				(width 0.1)
				(type default)
			)
			(layer "B.Fab")
		)
		(fp_line
			(start -0.299974 -0.150114)
			(end -0.299974 0.150114)
			(stroke
				(width 0.1)
				(type default)
			)
			(layer "B.Fab")
		)
		(fp_line
			(start 0.299974 -0.150114)
			(end -0.299974 -0.150114)
			(stroke
				(width 0.1)
				(type default)
			)
			(layer "B.Fab")
		)
		(pad "1" smd rect
			(at 0.2667 0 90)
			(size 0.3048 0.381)
			(layers "B.Cu" "B.Mask" "B.Paste")
			(net "P0V8_PEX1")
		)
		(pad "2" smd rect
			(at -0.2667 0 90)
			(size 0.3048 0.381)
			(layers "B.Cu" "B.Mask" "B.Paste")
			(net "GND")
		)
	)
	(footprint ""
		(layer "B.Cu")
		(at 121.642378 -260.509258 90)
		(property "Reference" "PR7135"
			(at 0 0 90)
			(layer "B.SilkS")
			(hide yes)
			(effects
				(font
					(size 1.27 1.27)
				)
				(justify mirror)
			)
		)
		(property "Value" ""
			(at 0 0 90)
			(layer "B.Fab")
			(effects
				(font
					(size 1.27 1.27)
				)
				(justify mirror)
			)
		)
		(duplicate_pad_numbers_are_jumpers no)
		(fp_line
			(start 0.7874 -0.4064)
			(end -0.7874 -0.4064)
			(stroke
				(width 0.1524)
				(type default)
			)
			(layer "B.SilkS")
		)
		(fp_line
			(start -0.7874 -0.4064)
			(end -0.7874 0.4064)
			(stroke
				(width 0.1524)
				(type default)
			)
			(layer "B.SilkS")
		)
		(fp_line
			(start 0.7874 0.4064)
			(end 0.7874 -0.4064)
			(stroke
				(width 0.1524)
				(type default)
			)
			(layer "B.SilkS")
		)
		(fp_line
			(start -0.7874 0.4064)
			(end 0.7874 0.4064)
			(stroke
				(width 0.1524)
				(type default)
			)
			(layer "B.SilkS")
		)
		(fp_line
			(start 0.67945 -0.305054)
			(end 0.12065 -0.305054)
			(stroke
				(width 0.1)
				(type default)
			)
			(layer "B.Fab")
		)
		(fp_line
			(start 0.12065 -0.305054)
			(end 0.12065 -0.2794)
			(stroke
				(width 0.1)
				(type default)
			)
			(layer "B.Fab")
		)
		(fp_line
			(start -0.12065 -0.3048)
			(end -0.67945 -0.3048)
			(stroke
				(width 0.1)
				(type default)
			)
			(layer "B.Fab")
		)
		(fp_line
			(start -0.67945 -0.3048)
			(end -0.67945 0.3048)
			(stroke
				(width 0.1)
				(type default)
			)
			(layer "B.Fab")
		)
		(fp_line
			(start 0.12065 -0.2794)
			(end -0.12065 -0.2794)
			(stroke
				(width 0.1)
				(type default)
			)
			(layer "B.Fab")
		)
		(fp_line
			(start -0.12065 -0.2794)
			(end -0.12065 -0.3048)
			(stroke
				(width 0.1)
				(type default)
			)
			(layer "B.Fab")
		)
		(fp_line
			(start 0.12065 0.2794)
			(end 0.12065 0.3048)
			(stroke
				(width 0.1)
				(type default)
			)
			(layer "B.Fab")
		)
		(fp_line
			(start -0.120396 0.2794)
			(end 0.12065 0.2794)
			(stroke
				(width 0.1)
				(type default)
			)
			(layer "B.Fab")
		)
		(fp_line
			(start 0.67945 0.3048)
			(end 0.67945 -0.305054)
			(stroke
				(width 0.1)
				(type default)
			)
			(layer "B.Fab")
		)
		(fp_line
			(start 0.12065 0.3048)
			(end 0.67945 0.3048)
			(stroke
				(width 0.1)
				(type default)
			)
			(layer "B.Fab")
		)
		(fp_line
			(start -0.120396 0.3048)
			(end -0.120396 0.2794)
			(stroke
				(width 0.1)
				(type default)
			)
			(layer "B.Fab")
		)
		(fp_line
			(start -0.67945 0.3048)
			(end -0.120396 0.3048)
			(stroke
				(width 0.1)
				(type default)
			)
			(layer "B.Fab")
		)
		(pad "1" smd circle
			(at 0.40005 0 270)
			(size 0 0)
			(layers "B.Cu" "B.Mask" "B.Paste")
			(net "NC_P0V8_PEX0_ISEN2")
		)
		(pad "2" smd circle
			(at -0.40005 0 270)
			(size 0 0)
			(layers "B.Cu" "B.Mask" "B.Paste")
			(net "GND")
		)
	)
	(footprint ""
		(layer "B.Cu")
		(at 121.050558 -308.580028 90)
		(property "Reference" "C1412"
			(at 0 0 90)
			(layer "B.SilkS")
			(hide yes)
			(effects
				(font
					(size 1.27 1.27)
				)
				(justify mirror)
			)
		)
		(property "Value" ""
			(at 0 0 90)
			(layer "B.Fab")
			(effects
				(font
					(size 1.27 1.27)
				)
				(justify mirror)
			)
		)
		(duplicate_pad_numbers_are_jumpers no)
		(fp_line
			(start 1.2954 -0.5842)
			(end -1.2954 -0.5842)
			(stroke
				(width 0.1524)
				(type default)
			)
			(layer "B.SilkS")
		)
		(fp_line
			(start -1.2954 -0.5842)
			(end -1.2954 0.5842)
			(stroke
				(width 0.1524)
				(type default)
			)
			(layer "B.SilkS")
		)
		(fp_line
			(start 1.2954 0.5842)
			(end 1.2954 -0.5842)
			(stroke
				(width 0.1524)
				(type default)
			)
			(layer "B.SilkS")
		)
		(fp_line
			(start -1.2954 0.5842)
			(end 1.2954 0.5842)
			(stroke
				(width 0.1524)
				(type default)
			)
			(layer "B.SilkS")
		)
		(fp_line
			(start 0.8636 -0.4572)
			(end -0.8636 -0.4572)
			(stroke
				(width 0.1)
				(type default)
			)
			(layer "B.Fab")
		)
		(fp_line
			(start -0.8636 -0.4572)
			(end -0.8636 -0.4064)
			(stroke
				(width 0.1)
				(type default)
			)
			(layer "B.Fab")
		)
		(fp_line
			(start 1.1938 -0.4064)
			(end 0.8636 -0.4064)
			(stroke
				(width 0.1)
				(type default)
			)
			(layer "B.Fab")
		)
		(fp_line
			(start 0.8636 -0.4064)
			(end 0.8636 -0.4572)
			(stroke
				(width 0.1)
				(type default)
			)
			(layer "B.Fab")
		)
		(fp_line
			(start -0.8636 -0.4064)
			(end -1.1938 -0.4064)
			(stroke
				(width 0.1)
				(type default)
			)
			(layer "B.Fab")
		)
		(fp_line
			(start -1.1938 -0.4064)
			(end -1.1938 0.4064)
			(stroke
				(width 0.1)
				(type default)
			)
			(layer "B.Fab")
		)
		(fp_line
			(start 1.1938 0.4064)
			(end 1.1938 -0.4064)
			(stroke
				(width 0.1)
				(type default)
			)
			(layer "B.Fab")
		)
		(fp_line
			(start 0.8636 0.4064)
			(end 1.1938 0.4064)
			(stroke
				(width 0.1)
				(type default)
			)
			(layer "B.Fab")
		)
		(fp_line
			(start -0.8636 0.4064)
			(end -0.8636 0.4572)
			(stroke
				(width 0.1)
				(type default)
			)
			(layer "B.Fab")
		)
		(fp_line
			(start -1.1938 0.4064)
			(end -0.8636 0.4064)
			(stroke
				(width 0.1)
				(type default)
			)
			(layer "B.Fab")
		)
		(fp_line
			(start 0.8636 0.4572)
			(end 0.8636 0.4064)
			(stroke
				(width 0.1)
				(type default)
			)
			(layer "B.Fab")
		)
		(fp_line
			(start -0.8636 0.4572)
			(end 0.8636 0.4572)
			(stroke
				(width 0.1)
				(type default)
			)
			(layer "B.Fab")
		)
		(pad "1" smd rect
			(at 0.7366 0)
			(size 0.7112 0.8128)
			(layers "B.Cu" "B.Mask" "B.Paste")
			(net "P0V8_SERDES_VDDA_PEX1")
		)
		(pad "2" smd rect
			(at -0.7366 0)
			(size 0.7112 0.8128)
			(layers "B.Cu" "B.Mask" "B.Paste")
			(net "GND")
		)
	)
	(footprint ""
		(layer "B.Cu")
		(at 418.40404 -98.552)
		(property "Reference" "R380"
			(at 0 0 0)
			(layer "B.SilkS")
			(hide yes)
			(effects
				(font
					(size 1.27 1.27)
				)
				(justify mirror)
			)
		)
		(property "Value" ""
			(at 0 0 0)
			(layer "B.Fab")
			(effects
				(font
					(size 1.27 1.27)
				)
				(justify mirror)
			)
		)
		(duplicate_pad_numbers_are_jumpers no)
		(fp_line
			(start -0.7874 -0.4064)
			(end -0.7874 0.4064)
			(stroke
				(width 0.1524)
				(type default)
			)
			(layer "B.SilkS")
		)
		(fp_line
			(start -0.7874 0.4064)
			(end 0.7874 0.4064)
			(stroke
				(width 0.1524)
				(type default)
			)
			(layer "B.SilkS")
		)
		(fp_line
			(start 0.7874 -0.4064)
			(end -0.7874 -0.4064)
			(stroke
				(width 0.1524)
				(type default)
			)
			(layer "B.SilkS")
		)
		(fp_line
			(start 0.7874 0.4064)
			(end 0.7874 -0.4064)
			(stroke
				(width 0.1524)
				(type default)
			)
			(layer "B.SilkS")
		)
		(fp_line
			(start -0.67945 -0.3048)
			(end -0.67945 0.3048)
			(stroke
				(width 0.1)
				(type default)
			)
			(layer "B.Fab")
		)
		(fp_line
			(start -0.67945 0.3048)
			(end -0.120396 0.3048)
			(stroke
				(width 0.1)
				(type default)
			)
			(layer "B.Fab")
		)
		(fp_line
			(start -0.12065 -0.3048)
			(end -0.67945 -0.3048)
			(stroke
				(width 0.1)
				(type default)
			)
			(layer "B.Fab")
		)
		(fp_line
			(start -0.12065 -0.2794)
			(end -0.12065 -0.3048)
			(stroke
				(width 0.1)
				(type default)
			)
			(layer "B.Fab")
		)
		(fp_line
			(start -0.120396 0.2794)
			(end 0.12065 0.2794)
			(stroke
				(width 0.1)
				(type default)
			)
			(layer "B.Fab")
		)
		(fp_line
			(start -0.120396 0.3048)
			(end -0.120396 0.2794)
			(stroke
				(width 0.1)
				(type default)
			)
			(layer "B.Fab")
		)
		(fp_line
			(start 0.12065 -0.305054)
			(end 0.12065 -0.2794)
			(stroke
				(width 0.1)
				(type default)
			)
			(layer "B.Fab")
		)
		(fp_line
			(start 0.12065 -0.2794)
			(end -0.12065 -0.2794)
			(stroke
				(width 0.1)
				(type default)
			)
			(layer "B.Fab")
		)
		(fp_line
			(start 0.12065 0.2794)
			(end 0.12065 0.3048)
			(stroke
				(width 0.1)
				(type default)
			)
			(layer "B.Fab")
		)
		(fp_line
			(start 0.12065 0.3048)
			(end 0.67945 0.3048)
			(stroke
				(width 0.1)
				(type default)
			)
			(layer "B.Fab")
		)
		(fp_line
			(start 0.67945 -0.305054)
			(end 0.12065 -0.305054)
			(stroke
				(width 0.1)
				(type default)
			)
			(layer "B.Fab")
		)
		(fp_line
			(start 0.67945 0.3048)
			(end 0.67945 -0.305054)
			(stroke
				(width 0.1)
				(type default)
			)
			(layer "B.Fab")
		)
		(pad "1" smd circle
			(at 0.40005 0 180)
			(size 0 0)
			(layers "B.Cu" "B.Mask" "B.Paste")
			(net "NIC7_MAIN_PWR_EN")
		)
		(pad "2" smd circle
			(at -0.40005 0 180)
			(size 0 0)
			(layers "B.Cu" "B.Mask" "B.Paste")
			(net "GND")
		)
	)
)
